(kicad_pcb
	(version 20241229)
	(generator "pcbnew")
	(generator_version "9.0")
	(general
		(thickness 1.62)
		(legacy_teardrops no)
	)
	(paper "A3")
	(title_block
		(title "COM Express 7 Baseboard")
		(date "2025-02-04")
		(rev "1.1.2")
		(company "Antmicro Ltd")
		(comment 1 "www.antmicro.com")
		(comment 9 "footprints 324-329 of 802")
	)
	(layers
		(0 "F.Cu" signal)
		(4 "In1.Cu" signal)
		(6 "In2.Cu" signal)
		(8 "In3.Cu" signal)
		(10 "In4.Cu" signal)
		(12 "In5.Cu" signal)
		(14 "In6.Cu" signal)
		(2 "B.Cu" signal)
		(9 "F.Adhes" user "F.Adhesive")
		(11 "B.Adhes" user "B.Adhesive")
		(13 "F.Paste" user)
		(15 "B.Paste" user)
		(5 "F.SilkS" user "F.Silkscreen")
		(7 "B.SilkS" user "B.Silkscreen")
		(1 "F.Mask" user)
		(3 "B.Mask" user)
		(17 "Dwgs.User" user "User.Drawings")
		(19 "Cmts.User" user "User.Comments")
		(21 "Eco1.User" user "User.Eco1")
		(23 "Eco2.User" user "User.Eco2")
		(25 "Edge.Cuts" user)
		(27 "Margin" user)
		(31 "F.CrtYd" user "F.Courtyard")
		(29 "B.CrtYd" user "B.Courtyard")
		(35 "F.Fab" user)
		(33 "B.Fab" user)
	)
	(footprint "antmicro-footprints:R_0201"
		(layer "F.Cu")
		(at 129.17 147.935 -90)
		(descr "Resistor SMD 0201")
		(tags "resistor SMD 0201")
		(property "Reference" "R313"
			(at 3.6 -0.58 90)
			(layer "F.SilkS")
			(effects
				(font
					(size 0.7 0.7)
					(thickness 0.15)
				)
				(justify right bottom)
			)
		)
		(property "Value" "R_0R_0201"
			(at 0 1.25 90)
			(layer "F.Fab")
			(effects
				(font
					(size 0.7 0.7)
					(thickness 0.15)
				)
				(justify right bottom)
			)
		)
		(property "Datasheet" "https://www.bourns.com/docs/product-datasheets/cr.pdf"
			(at 0 0 270)
			(layer "F.Fab")
			(hide yes)
			(effects
				(font
					(size 1.27 1.27)
					(thickness 0.15)
				)
			)
		)
		(property "Author" "Antmicro"
			(at -18.765 277.105 0)
			(layer "F.Fab")
			(hide yes)
			(effects
				(font
					(size 1 1)
					(thickness 0.15)
				)
			)
		)
		(property "License" "Apache-2.0"
			(at -18.765 277.105 0)
			(layer "F.Fab")
			(hide yes)
			(effects
				(font
					(size 1 1)
					(thickness 0.15)
				)
			)
		)
		(property "MPN" "CR0201-FX-0R00GLF"
			(at -18.765 277.105 0)
			(layer "F.Fab")
			(hide yes)
			(effects
				(font
					(size 1 1)
					(thickness 0.15)
				)
			)
		)
		(property "Manufacturer" "Bourns"
			(at -18.765 277.105 0)
			(layer "F.Fab")
			(hide yes)
			(effects
				(font
					(size 1 1)
					(thickness 0.15)
				)
			)
		)
		(property "Tolerance" "1%"
			(at -18.765 277.105 0)
			(layer "F.Fab")
			(hide yes)
			(effects
				(font
					(size 1 1)
					(thickness 0.15)
				)
			)
		)
		(property "Val" "0R"
			(at -18.765 277.105 0)
			(layer "F.Fab")
			(hide yes)
			(effects
				(font
					(size 1 1)
					(thickness 0.15)
				)
			)
		)
		(sheetname "KR to SFI #2")
		(sheetfile "kr_sfi.kicad_sch")
		(attr smd dnp)
		(fp_rect
			(start -0.7 -0.35)
			(end 0.7 0.35)
			(stroke
				(width 0.05)
				(type default)
			)
			(fill no)
			(layer "F.CrtYd")
		)
		(fp_rect
			(start -0.3 -0.15)
			(end 0.298 0.148)
			(stroke
				(width 0.15)
				(type solid)
			)
			(fill no)
			(layer "F.Fab")
		)
		(pad "" smd roundrect
			(at -0.346 0 270)
			(size 0.318 0.36)
			(layers "F.Paste")
			(roundrect_rratio 0.25)
			(teardrops
				(best_length_ratio 0.2)
				(max_length 1)
				(best_width_ratio 0.9)
				(max_width 2)
				(curved_edges yes)
				(filter_ratio 0.9)
				(enabled yes)
				(allow_two_segments yes)
				(prefer_zone_connections yes)
			)
		)
		(pad "" smd roundrect
			(at 0.344 0 270)
			(size 0.318 0.36)
			(layers "F.Paste")
			(roundrect_rratio 0.25)
			(teardrops
				(best_length_ratio 0.2)
				(max_length 1)
				(best_width_ratio 0.9)
				(max_width 2)
				(curved_edges yes)
				(filter_ratio 0.9)
				(enabled yes)
				(allow_two_segments yes)
				(prefer_zone_connections yes)
			)
		)
		(pad "1" smd roundrect
			(at -0.32 0 270)
			(size 0.46 0.4)
			(layers "F.Cu" "F.Mask")
			(roundrect_rratio 0.25)
			(net 879 "/2xSFP+/SFI1.TX+")
			(pintype "passive")
			(teardrops
				(best_length_ratio 0.2)
				(max_length 1)
				(best_width_ratio 0.9)
				(max_width 2)
				(curved_edges yes)
				(filter_ratio 0.9)
				(enabled yes)
				(allow_two_segments yes)
				(prefer_zone_connections yes)
			)
		)
		(pad "2" smd roundrect
			(at 0.32 0 270)
			(size 0.46 0.4)
			(layers "F.Cu" "F.Mask")
			(roundrect_rratio 0.25)
			(net 955 "/2xSFP+/KR to SFI #2/BYP_TX+")
			(pintype "passive")
			(teardrops
				(best_length_ratio 0.2)
				(max_length 1)
				(best_width_ratio 0.9)
				(max_width 2)
				(curved_edges yes)
				(filter_ratio 0.9)
				(enabled yes)
				(allow_two_segments yes)
				(prefer_zone_connections yes)
			)
		)
	)
	(footprint "antmicro-footprints:R_0402_1005Metric"
		(layer "F.Cu")
		(at 128.9 81.76 -90)
		(descr "Resistor SMD 0402")
		(tags "resistor SMD 0402")
		(property "Reference" "R237"
			(at -3.650001 -0.45 90)
			(layer "F.SilkS")
			(effects
				(font
					(size 0.7 0.7)
					(thickness 0.15)
				)
				(justify right bottom)
			)
		)
		(property "Value" "R_0R_0402"
			(at -1.011843 1.772047 90)
			(layer "F.Fab")
			(effects
				(font
					(size 0.7 0.7)
					(thickness 0.15)
				)
				(justify right bottom)
			)
		)
		(property "Datasheet" "https://industrial.panasonic.com/cdbs/www-data/pdf/RDA0000/AOA0000C301.pdf"
			(at 0 0 270)
			(layer "F.Fab")
			(hide yes)
			(effects
				(font
					(size 1.27 1.27)
					(thickness 0.15)
				)
			)
		)
		(property "Author" "Antmicro"
			(at 47.14 210.66 0)
			(layer "F.Fab")
			(hide yes)
			(effects
				(font
					(size 1 1)
					(thickness 0.15)
				)
			)
		)
		(property "Current" "1A"
			(at 47.14 210.66 0)
			(layer "F.Fab")
			(hide yes)
			(effects
				(font
					(size 1 1)
					(thickness 0.15)
				)
			)
		)
		(property "License" "Apache-2.0"
			(at 47.14 210.66 0)
			(layer "F.Fab")
			(hide yes)
			(effects
				(font
					(size 1 1)
					(thickness 0.15)
				)
			)
		)
		(property "MPN" "ERJ2GE0R00X"
			(at 47.14 210.66 0)
			(layer "F.Fab")
			(hide yes)
			(effects
				(font
					(size 1 1)
					(thickness 0.15)
				)
			)
		)
		(property "Manufacturer" "Panasonic"
			(at 47.14 210.66 0)
			(layer "F.Fab")
			(hide yes)
			(effects
				(font
					(size 1 1)
					(thickness 0.15)
				)
			)
		)
		(property "Public" "False"
			(at 47.14 210.66 0)
			(layer "F.Fab")
			(hide yes)
			(effects
				(font
					(size 1 1)
					(thickness 0.15)
				)
			)
		)
		(property "Tolerance" ""
			(at 47.14 210.66 0)
			(layer "F.Fab")
			(hide yes)
			(effects
				(font
					(size 1 1)
					(thickness 0.15)
				)
			)
		)
		(property "Val" "0R"
			(at 47.14 210.66 0)
			(layer "F.Fab")
			(hide yes)
			(effects
				(font
					(size 1 1)
					(thickness 0.15)
				)
			)
		)
		(sheetname "GPIO expander")
		(sheetfile "gpio_exp.kicad_sch")
		(attr smd)
		(fp_rect
			(start -0.925 -0.47)
			(end 0.925 0.47)
			(stroke
				(width 0.05)
				(type default)
			)
			(fill no)
			(layer "F.CrtYd")
		)
		(fp_rect
			(start -0.5 -0.25)
			(end 0.5 0.25)
			(stroke
				(width 0.15)
				(type solid)
			)
			(fill no)
			(layer "F.Fab")
		)
		(pad "1" smd roundrect
			(at -0.48 0 270)
			(size 0.59 0.64)
			(layers "F.Cu" "F.Mask" "F.Paste")
			(roundrect_rratio 0.25)
			(net 1 "GND")
			(pintype "passive")
			(teardrops
				(best_length_ratio 0.2)
				(max_length 1)
				(best_width_ratio 0.9)
				(max_width 2)
				(curved_edges yes)
				(filter_ratio 0.9)
				(enabled yes)
				(allow_two_segments yes)
				(prefer_zone_connections yes)
			)
		)
		(pad "2" smd roundrect
			(at 0.48 0 270)
			(size 0.59 0.64)
			(layers "F.Cu" "F.Mask" "F.Paste")
			(roundrect_rratio 0.25)
			(net 638 "Net-(U41-A1)")
			(pintype "passive")
			(teardrops
				(best_length_ratio 0.2)
				(max_length 1)
				(best_width_ratio 0.9)
				(max_width 2)
				(curved_edges yes)
				(filter_ratio 0.9)
				(enabled yes)
				(allow_two_segments yes)
				(prefer_zone_connections yes)
			)
		)
	)
	(footprint "antmicro-footprints:R_0402_1005Metric"
		(layer "F.Cu")
		(at 124.84 133.88)
		(descr "Resistor SMD 0402")
		(tags "resistor SMD 0402")
		(property "Reference" "R305"
			(at -3.69 0.43 0)
			(layer "F.SilkS")
			(effects
				(font
					(size 0.7 0.7)
					(thickness 0.15)
				)
				(justify left bottom)
			)
		)
		(property "Value" "R_10k_0402"
			(at -1.011843 1.772047 0)
			(layer "F.Fab")
			(effects
				(font
					(size 0.7 0.7)
					(thickness 0.15)
				)
				(justify left bottom)
			)
		)
		(property "Datasheet" "https://www.bourns.com/docs/product-datasheets/cr.pdf"
			(at 0 0 0)
			(layer "F.Fab")
			(hide yes)
			(effects
				(font
					(size 1.27 1.27)
					(thickness 0.15)
				)
			)
		)
		(property "Author" "Antmicro"
			(at 0 0 0)
			(layer "F.Fab")
			(hide yes)
			(effects
				(font
					(size 1 1)
					(thickness 0.15)
				)
			)
		)
		(property "License" "Apache-2.0"
			(at 0 0 0)
			(layer "F.Fab")
			(hide yes)
			(effects
				(font
					(size 1 1)
					(thickness 0.15)
				)
			)
		)
		(property "MPN" "CR0402-FX-1002GLF"
			(at 0 0 0)
			(layer "F.Fab")
			(hide yes)
			(effects
				(font
					(size 1 1)
					(thickness 0.15)
				)
			)
		)
		(property "Manufacturer" "Bourns"
			(at 0 0 0)
			(layer "F.Fab")
			(hide yes)
			(effects
				(font
					(size 1 1)
					(thickness 0.15)
				)
			)
		)
		(property "Public" "False"
			(at 0 0 0)
			(layer "F.Fab")
			(hide yes)
			(effects
				(font
					(size 1 1)
					(thickness 0.15)
				)
			)
		)
		(property "Tolerance" "1%"
			(at 0 0 0)
			(layer "F.Fab")
			(hide yes)
			(effects
				(font
					(size 1 1)
					(thickness 0.15)
				)
			)
		)
		(property "Val" "10k"
			(at 0 0 0)
			(layer "F.Fab")
			(hide yes)
			(effects
				(font
					(size 1 1)
					(thickness 0.15)
				)
			)
		)
		(sheetname "KR to SFI #2")
		(sheetfile "kr_sfi.kicad_sch")
		(attr smd)
		(fp_rect
			(start -0.925 -0.47)
			(end 0.925 0.47)
			(stroke
				(width 0.05)
				(type default)
			)
			(fill no)
			(layer "F.CrtYd")
		)
		(fp_rect
			(start -0.5 -0.25)
			(end 0.5 0.25)
			(stroke
				(width 0.15)
				(type solid)
			)
			(fill no)
			(layer "F.Fab")
		)
		(pad "1" smd roundrect
			(at -0.48 0)
			(size 0.59 0.64)
			(layers "F.Cu" "F.Mask" "F.Paste")
			(roundrect_rratio 0.25)
			(net 1 "GND")
			(pintype "passive")
			(teardrops
				(best_length_ratio 0.2)
				(max_length 1)
				(best_width_ratio 0.9)
				(max_width 2)
				(curved_edges yes)
				(filter_ratio 0.9)
				(enabled yes)
				(allow_two_segments yes)
				(prefer_zone_connections yes)
			)
		)
		(pad "2" smd roundrect
			(at 0.48 0)
			(size 0.59 0.64)
			(layers "F.Cu" "F.Mask" "F.Paste")
			(roundrect_rratio 0.25)
			(net 684 "Net-(U45C-ST)")
			(pintype "passive")
			(teardrops
				(best_length_ratio 0.2)
				(max_length 1)
				(best_width_ratio 0.9)
				(max_width 2)
				(curved_edges yes)
				(filter_ratio 0.9)
				(enabled yes)
				(allow_two_segments yes)
				(prefer_zone_connections yes)
			)
		)
	)
	(footprint "antmicro-footprints:R_0201"
		(layer "F.Cu")
		(at 152.57 147.935 -90)
		(descr "Resistor SMD 0201")
		(tags "resistor SMD 0201")
		(property "Reference" "R250"
			(at 6.495 -0.28 270)
			(layer "F.SilkS")
			(effects
				(font
					(size 0.7 0.7)
					(thickness 0.15)
				)
				(justify left bottom)
			)
		)
		(property "Value" "R_0R_0201"
			(at 0 1.25 270)
			(layer "F.Fab")
			(effects
				(font
					(size 0.7 0.7)
					(thickness 0.15)
				)
				(justify left bottom)
			)
		)
		(property "Datasheet" "https://www.bourns.com/docs/product-datasheets/cr.pdf"
			(at 0 0 270)
			(layer "F.Fab")
			(hide yes)
			(effects
				(font
					(size 1.27 1.27)
					(thickness 0.15)
				)
			)
		)
		(property "Author" "Antmicro"
			(at 4.635 300.505 0)
			(layer "F.Fab")
			(hide yes)
			(effects
				(font
					(size 1 1)
					(thickness 0.15)
				)
			)
		)
		(property "License" "Apache-2.0"
			(at 4.635 300.505 0)
			(layer "F.Fab")
			(hide yes)
			(effects
				(font
					(size 1 1)
					(thickness 0.15)
				)
			)
		)
		(property "MPN" "CR0201-FX-0R00GLF"
			(at 4.635 300.505 0)
			(layer "F.Fab")
			(hide yes)
			(effects
				(font
					(size 1 1)
					(thickness 0.15)
				)
			)
		)
		(property "Manufacturer" "Bourns"
			(at 4.635 300.505 0)
			(layer "F.Fab")
			(hide yes)
			(effects
				(font
					(size 1 1)
					(thickness 0.15)
				)
			)
		)
		(property "Tolerance" "1%"
			(at 4.635 300.505 0)
			(layer "F.Fab")
			(hide yes)
			(effects
				(font
					(size 1 1)
					(thickness 0.15)
				)
			)
		)
		(property "Val" "0R"
			(at 4.635 300.505 0)
			(layer "F.Fab")
			(hide yes)
			(effects
				(font
					(size 1 1)
					(thickness 0.15)
				)
			)
		)
		(sheetname "KR to SFI #1")
		(sheetfile "kr_sfi.kicad_sch")
		(attr smd dnp)
		(fp_rect
			(start -0.7 -0.35)
			(end 0.7 0.35)
			(stroke
				(width 0.05)
				(type default)
			)
			(fill no)
			(layer "F.CrtYd")
		)
		(fp_rect
			(start -0.3 -0.15)
			(end 0.298 0.148)
			(stroke
				(width 0.15)
				(type solid)
			)
			(fill no)
			(layer "F.Fab")
		)
		(pad "" smd roundrect
			(at -0.346 0 270)
			(size 0.318 0.36)
			(layers "F.Paste")
			(roundrect_rratio 0.25)
			(teardrops
				(best_length_ratio 0.2)
				(max_length 1)
				(best_width_ratio 0.9)
				(max_width 2)
				(curved_edges yes)
				(filter_ratio 0.9)
				(enabled yes)
				(allow_two_segments yes)
				(prefer_zone_connections yes)
			)
		)
		(pad "" smd roundrect
			(at 0.344 0 270)
			(size 0.318 0.36)
			(layers "F.Paste")
			(roundrect_rratio 0.25)
			(teardrops
				(best_length_ratio 0.2)
				(max_length 1)
				(best_width_ratio 0.9)
				(max_width 2)
				(curved_edges yes)
				(filter_ratio 0.9)
				(enabled yes)
				(allow_two_segments yes)
				(prefer_zone_connections yes)
			)
		)
		(pad "1" smd roundrect
			(at -0.32 0 270)
			(size 0.46 0.4)
			(layers "F.Cu" "F.Mask")
			(roundrect_rratio 0.25)
			(net 433 "/2xSFP+/10GKR_SFP0.RX-")
			(pintype "passive")
			(teardrops
				(best_length_ratio 0.2)
				(max_length 1)
				(best_width_ratio 0.9)
				(max_width 2)
				(curved_edges yes)
				(filter_ratio 0.9)
				(enabled yes)
				(allow_two_segments yes)
				(prefer_zone_connections yes)
			)
		)
		(pad "2" smd roundrect
			(at 0.32 0 270)
			(size 0.46 0.4)
			(layers "F.Cu" "F.Mask")
			(roundrect_rratio 0.25)
			(net 967 "/2xSFP+/KR to SFI #1/BYP_RX-")
			(pintype "passive")
			(teardrops
				(best_length_ratio 0.2)
				(max_length 1)
				(best_width_ratio 0.9)
				(max_width 2)
				(curved_edges yes)
				(filter_ratio 0.9)
				(enabled yes)
				(allow_two_segments yes)
				(prefer_zone_connections yes)
			)
		)
	)
	(footprint "antmicro-footprints:R_0201"
		(layer "F.Cu")
		(at 131.41 147.336 -90)
		(descr "Resistor SMD 0201")
		(tags "resistor SMD 0201")
		(property "Reference" "R307"
			(at 4.073 -0.29 270)
			(layer "F.SilkS")
			(effects
				(font
					(size 0.7 0.7)
					(thickness 0.15)
				)
				(justify left bottom)
			)
		)
		(property "Value" "R_0R_0201"
			(at 0 1.25 270)
			(layer "F.Fab")
			(effects
				(font
					(size 0.7 0.7)
					(thickness 0.15)
				)
				(justify left bottom)
			)
		)
		(property "Datasheet" "https://www.bourns.com/docs/product-datasheets/cr.pdf"
			(at 0 0 270)
			(layer "F.Fab")
			(hide yes)
			(effects
				(font
					(size 1.27 1.27)
					(thickness 0.15)
				)
			)
		)
		(property "Author" "Antmicro"
			(at -15.926 278.746 0)
			(layer "F.Fab")
			(hide yes)
			(effects
				(font
					(size 1 1)
					(thickness 0.15)
				)
			)
		)
		(property "License" "Apache-2.0"
			(at -15.926 278.746 0)
			(layer "F.Fab")
			(hide yes)
			(effects
				(font
					(size 1 1)
					(thickness 0.15)
				)
			)
		)
		(property "MPN" "CR0201-FX-0R00GLF"
			(at -15.926 278.746 0)
			(layer "F.Fab")
			(hide yes)
			(effects
				(font
					(size 1 1)
					(thickness 0.15)
				)
			)
		)
		(property "Manufacturer" "Bourns"
			(at -15.926 278.746 0)
			(layer "F.Fab")
			(hide yes)
			(effects
				(font
					(size 1 1)
					(thickness 0.15)
				)
			)
		)
		(property "Tolerance" "1%"
			(at -15.926 278.746 0)
			(layer "F.Fab")
			(hide yes)
			(effects
				(font
					(size 1 1)
					(thickness 0.15)
				)
			)
		)
		(property "Val" "0R"
			(at -15.926 278.746 0)
			(layer "F.Fab")
			(hide yes)
			(effects
				(font
					(size 1 1)
					(thickness 0.15)
				)
			)
		)
		(sheetname "KR to SFI #2")
		(sheetfile "kr_sfi.kicad_sch")
		(attr smd)
		(fp_rect
			(start -0.7 -0.35)
			(end 0.7 0.35)
			(stroke
				(width 0.05)
				(type default)
			)
			(fill no)
			(layer "F.CrtYd")
		)
		(fp_rect
			(start -0.3 -0.15)
			(end 0.298 0.148)
			(stroke
				(width 0.15)
				(type solid)
			)
			(fill no)
			(layer "F.Fab")
		)
		(pad "" smd roundrect
			(at -0.346 0 270)
			(size 0.318 0.36)
			(layers "F.Paste")
			(roundrect_rratio 0.25)
			(teardrops
				(best_length_ratio 0.2)
				(max_length 1)
				(best_width_ratio 0.9)
				(max_width 2)
				(curved_edges yes)
				(filter_ratio 0.9)
				(enabled yes)
				(allow_two_segments yes)
				(prefer_zone_connections yes)
			)
		)
		(pad "" smd roundrect
			(at 0.344 0 270)
			(size 0.318 0.36)
			(layers "F.Paste")
			(roundrect_rratio 0.25)
			(teardrops
				(best_length_ratio 0.2)
				(max_length 1)
				(best_width_ratio 0.9)
				(max_width 2)
				(curved_edges yes)
				(filter_ratio 0.9)
				(enabled yes)
				(allow_two_segments yes)
				(prefer_zone_connections yes)
			)
		)
		(pad "1" smd roundrect
			(at -0.32 0 270)
			(size 0.46 0.4)
			(layers "F.Cu" "F.Mask")
			(roundrect_rratio 0.25)
			(net 950 "/2xSFP+/KR to SFI #2/SFI_R.RX+")
			(pintype "passive")
			(teardrops
				(best_length_ratio 0.2)
				(max_length 1)
				(best_width_ratio 0.9)
				(max_width 2)
				(curved_edges yes)
				(filter_ratio 0.9)
				(enabled yes)
				(allow_two_segments yes)
				(prefer_zone_connections yes)
			)
		)
		(pad "2" smd roundrect
			(at 0.32 0 270)
			(size 0.46 0.4)
			(layers "F.Cu" "F.Mask")
			(roundrect_rratio 0.25)
			(net 878 "/2xSFP+/SFI1.RX+")
			(pintype "passive")
			(teardrops
				(best_length_ratio 0.2)
				(max_length 1)
				(best_width_ratio 0.9)
				(max_width 2)
				(curved_edges yes)
				(filter_ratio 0.9)
				(enabled yes)
				(allow_two_segments yes)
				(prefer_zone_connections yes)
			)
		)
	)
	(footprint "antmicro-footprints:TP_SMD_0.75mm"
		(layer "F.Cu")
		(at 129.74 128.71)
		(property "Reference" "TP85"
			(at 0.51 -3.3 90)
			(layer "F.SilkS")
			(effects
				(font
					(size 0.7 0.7)
					(thickness 0.15)
				)
				(justify left bottom)
			)
		)
		(property "Value" "TP_0.75mm_SMD"
			(at 0 1.2 0)
			(layer "F.Fab")
			(effects
				(font
					(size 0.7 0.7)
					(thickness 0.15)
				)
				(justify left bottom)
			)
		)
		(property "Author" "Antmicro"
			(at 0 0 0)
			(layer "F.Fab")
			(hide yes)
			(effects
				(font
					(size 1 1)
					(thickness 0.15)
				)
			)
		)
		(property "License" "Apache-2.0"
			(at 0 0 0)
			(layer "F.Fab")
			(hide yes)
			(effects
				(font
					(size 1 1)
					(thickness 0.15)
				)
			)
		)
		(property "MPN" ""
			(at 0 0 0)
			(layer "F.Fab")
			(hide yes)
			(effects
				(font
					(size 1 1)
					(thickness 0.15)
				)
			)
		)
		(property "Manufacturer" ""
			(at 0 0 0)
			(layer "F.Fab")
			(hide yes)
			(effects
				(font
					(size 1 1)
					(thickness 0.15)
				)
			)
		)
		(property "Public" "False"
			(at 0 0 0)
			(layer "F.Fab")
			(hide yes)
			(effects
				(font
					(size 1 1)
					(thickness 0.15)
				)
			)
		)
		(sheetname "KR to SFI #2")
		(sheetfile "kr_sfi.kicad_sch")
		(attr exclude_from_pos_files exclude_from_bom)
		(fp_circle
			(center 0 0)
			(end 0.475 0)
			(stroke
				(width 0.05)
				(type default)
			)
			(fill no)
			(layer "F.CrtYd")
		)
		(pad "1" smd circle
			(at 0 0)
			(size 0.75 0.75)
			(layers "F.Cu" "F.Mask")
			(net 748 "Net-(U45C-AMUXA)")
			(pinfunction "1")
			(pintype "passive")
			(teardrops
				(best_length_ratio 0.4)
				(max_length 1)
				(best_width_ratio 0.9)
				(max_width 2)
				(curved_edges yes)
				(filter_ratio 0.9)
				(enabled yes)
				(allow_two_segments yes)
				(prefer_zone_connections yes)
			)
		)
	)
)
